(kicad_pcb
	(version 20260206)
	(generator "pcbnew")
	(generator_version "10.0")
	(general
		(thickness 1.6)
		(legacy_teardrops no)
	)
	(paper "A4")
	(title_block
		(title "v1-chassis-manager — T6M_CM_d_v01_1031_1645.brd")
		(comment 1 "Open CloudServer (Microsoft) / footprints 2243-2252 of 2512")
	)
	(layers
		(0 "F.Cu" signal "TOP")
		(4 "In1.Cu" signal "GND1")
		(6 "In2.Cu" signal "IN1")
		(8 "In3.Cu" signal "VCC1")
		(10 "In4.Cu" signal "VCC2")
		(12 "In5.Cu" signal "GND2")
		(14 "In6.Cu" signal "IN2")
		(16 "In7.Cu" signal "IN3")
		(18 "In8.Cu" signal "GND3")
		(2 "B.Cu" signal "BOTTOM")
		(9 "F.Adhes" user "F.Adhesive")
		(11 "B.Adhes" user "B.Adhesive")
		(13 "F.Paste" user "Package Geometry/Pastemask Top")
		(15 "B.Paste" user "Package Geometry/Pastemask Bottom")
		(5 "F.SilkS" user "Ref Des/Silkscreen Top")
		(7 "B.SilkS" user "Ref Des/Silkscreen Bottom")
		(1 "F.Mask" user "Board Geometry/Soldermask Top")
		(3 "B.Mask" user "Board Geometry/Soldermask Bottom")
		(17 "Dwgs.User" user "User.Drawings")
		(19 "Cmts.User" user "User.Comments")
		(21 "Eco1.User" user "User.Eco1")
		(23 "Eco2.User" user "User.Eco2")
		(25 "Edge.Cuts" user "Board Geometry/Outline")
		(27 "Margin" user)
		(31 "F.CrtYd" user "Package Geometry/Place Bound Top")
		(29 "B.CrtYd" user "Package Geometry/Place Bound Bottom")
		(35 "F.Fab" user "Ref Des/Assembly Top")
		(33 "B.Fab" user "Ref Des/Assembly Bottom")
	)
	(footprint ""
		(layer "B.Cu")
		(at 125.866652 -143.00835 180)
		(property "Reference" "C894"
			(at 3.235198 3.495294 0)
			(unlocked yes)
			(layer "B.SilkS")
			(effects
				(font
					(size 0.7874 0.5842)
					(thickness 0.1524)
				)
				(justify left mirror)
			)
		)
		(property "Value" ""
			(at 0 0 0)
			(layer "B.Fab")
			(effects
				(font
					(size 1.27 1.27)
				)
				(justify mirror)
			)
		)
		(duplicate_pad_numbers_are_jumpers no)
		(fp_line
			(start 0.7874 0.4064)
			(end 0.7874 -0.4064)
			(stroke
				(width 0.1524)
				(type default)
			)
			(layer "B.SilkS")
		)
		(fp_line
			(start 0.7874 -0.4064)
			(end -0.7874 -0.4064)
			(stroke
				(width 0.1524)
				(type default)
			)
			(layer "B.SilkS")
		)
		(fp_line
			(start 0 0.381)
			(end 0 -0.381)
			(stroke
				(width 0.1524)
				(type default)
			)
			(layer "B.SilkS")
		)
		(fp_line
			(start -0.7874 0.4064)
			(end 0.7874 0.4064)
			(stroke
				(width 0.1524)
				(type default)
			)
			(layer "B.SilkS")
		)
		(fp_line
			(start -0.7874 -0.4064)
			(end -0.7874 0.4064)
			(stroke
				(width 0.1524)
				(type default)
			)
			(layer "B.SilkS")
		)
		(fp_poly
			(pts
				(xy 0.5334 0.254) (xy 0.635 0.254) (xy 0.635 0.2286) (xy 0.635 -0.254) (xy 0.5334 -0.254) (xy 0.5334 -0.2794)
				(xy -0.5334 -0.2794) (xy -0.5334 -0.254) (xy -0.635 -0.254) (xy -0.635 0.254) (xy -0.5334 0.254)
				(xy -0.5334 0.2794) (xy 0.508 0.2794) (xy 0.5334 0.2794)
			)
			(stroke
				(width 0)
				(type default)
			)
			(fill no)
			(layer "B.CrtYd")
		)
		(pad "1" smd rect
			(at -0.40005 0)
			(size 0.4572 0.508)
			(layers "B.Cu" "B.Mask" "B.Paste")
			(net "P1V538_BMC_NODE1")
		)
		(pad "2" smd rect
			(at 0.40005 0)
			(size 0.4572 0.508)
			(layers "B.Cu" "B.Mask" "B.Paste")
			(net "GND")
		)
	)
	(footprint ""
		(layer "B.Cu")
		(at 56.24576 -188.126624 -90)
		(property "Reference" "C691"
			(at -4.276598 -0.065024 270)
			(unlocked yes)
			(layer "B.SilkS")
			(effects
				(font
					(size 0.7874 0.5842)
					(thickness 0.1524)
				)
				(justify left mirror)
			)
		)
		(property "Value" ""
			(at 0 0 90)
			(layer "B.Fab")
			(effects
				(font
					(size 1.27 1.27)
				)
				(justify mirror)
			)
		)
		(duplicate_pad_numbers_are_jumpers no)
		(fp_line
			(start -0.7874 0.4064)
			(end 0.7874 0.4064)
			(stroke
				(width 0.1524)
				(type default)
			)
			(layer "B.SilkS")
		)
		(fp_line
			(start 0.7874 0.4064)
			(end 0.7874 -0.4064)
			(stroke
				(width 0.1524)
				(type default)
			)
			(layer "B.SilkS")
		)
		(fp_line
			(start 0 0.381)
			(end 0 -0.381)
			(stroke
				(width 0.1524)
				(type default)
			)
			(layer "B.SilkS")
		)
		(fp_line
			(start -0.7874 -0.4064)
			(end -0.7874 0.4064)
			(stroke
				(width 0.1524)
				(type default)
			)
			(layer "B.SilkS")
		)
		(fp_line
			(start 0.7874 -0.4064)
			(end -0.7874 -0.4064)
			(stroke
				(width 0.1524)
				(type default)
			)
			(layer "B.SilkS")
		)
		(fp_poly
			(pts
				(xy 0.5334 0.254) (xy 0.635 0.254) (xy 0.635 0.2286) (xy 0.635 -0.254) (xy 0.5334 -0.254) (xy 0.5334 -0.2794)
				(xy -0.5334 -0.2794) (xy -0.5334 -0.254) (xy -0.635 -0.254) (xy -0.635 0.254) (xy -0.5334 0.254)
				(xy -0.5334 0.2794) (xy 0.508 0.2794) (xy 0.5334 0.2794)
			)
			(stroke
				(width 0)
				(type default)
			)
			(fill no)
			(layer "B.CrtYd")
		)
		(pad "1" smd rect
			(at -0.40005 0 90)
			(size 0.4572 0.508)
			(layers "B.Cu" "B.Mask" "B.Paste")
			(net "UART_T1_NODE4_TXD_R")
		)
		(pad "2" smd rect
			(at 0.40005 0 90)
			(size 0.4572 0.508)
			(layers "B.Cu" "B.Mask" "B.Paste")
			(net "GND")
		)
	)
	(footprint ""
		(layer "B.Cu")
		(at 94.451932 -174.156624)
		(property "Reference" "R708"
			(at 1.83642 14.281658 0)
			(unlocked yes)
			(layer "B.SilkS")
			(effects
				(font
					(size 0.7874 0.5842)
					(thickness 0.1524)
				)
				(justify left mirror)
			)
		)
		(property "Value" ""
			(at 0 0 0)
			(layer "B.Fab")
			(effects
				(font
					(size 1.27 1.27)
				)
				(justify mirror)
			)
		)
		(duplicate_pad_numbers_are_jumpers no)
		(fp_line
			(start -0.7874 -0.4064)
			(end -0.7874 0.4064)
			(stroke
				(width 0.1524)
				(type default)
			)
			(layer "B.SilkS")
		)
		(fp_line
			(start -0.7874 0.4064)
			(end 0.7874 0.4064)
			(stroke
				(width 0.1524)
				(type default)
			)
			(layer "B.SilkS")
		)
		(fp_line
			(start 0.7874 -0.4064)
			(end -0.7874 -0.4064)
			(stroke
				(width 0.1524)
				(type default)
			)
			(layer "B.SilkS")
		)
		(fp_line
			(start 0.7874 0.4064)
			(end 0.7874 -0.4064)
			(stroke
				(width 0.1524)
				(type default)
			)
			(layer "B.SilkS")
		)
		(fp_poly
			(pts
				(xy 0.508 0.2794) (xy 0.508 0.2286) (xy 0.635 0.2286) (xy 0.635 -0.254) (xy 0.5334 -0.254) (xy 0.5334 -0.2794)
				(xy -0.5334 -0.2794) (xy -0.5334 -0.254) (xy -0.635 -0.254) (xy -0.635 0.254) (xy -0.5334 0.254)
				(xy -0.5334 0.2794)
			)
			(stroke
				(width 0)
				(type default)
			)
			(fill no)
			(layer "B.CrtYd")
		)
		(pad "1" smd rect
			(at -0.40005 0 180)
			(size 0.4572 0.508)
			(layers "B.Cu" "B.Mask" "B.Paste")
			(net "P3V3_NODE1")
		)
		(pad "2" smd rect
			(at 0.40005 0 180)
			(size 0.4572 0.508)
			(layers "B.Cu" "B.Mask" "B.Paste")
			(net "N21701261")
		)
	)
	(footprint ""
		(layer "B.Cu")
		(at 59.67476 -185.205624 -90)
		(property "Reference" "C682"
			(at -4.15163 -0.200406 270)
			(unlocked yes)
			(layer "B.SilkS")
			(effects
				(font
					(size 0.7874 0.5842)
					(thickness 0.1524)
				)
				(justify left mirror)
			)
		)
		(property "Value" ""
			(at 0 0 90)
			(layer "B.Fab")
			(effects
				(font
					(size 1.27 1.27)
				)
				(justify mirror)
			)
		)
		(duplicate_pad_numbers_are_jumpers no)
		(fp_line
			(start -0.7874 0.4064)
			(end 0.7874 0.4064)
			(stroke
				(width 0.1524)
				(type default)
			)
			(layer "B.SilkS")
		)
		(fp_line
			(start 0.7874 0.4064)
			(end 0.7874 -0.4064)
			(stroke
				(width 0.1524)
				(type default)
			)
			(layer "B.SilkS")
		)
		(fp_line
			(start 0 0.381)
			(end 0 -0.381)
			(stroke
				(width 0.1524)
				(type default)
			)
			(layer "B.SilkS")
		)
		(fp_line
			(start -0.7874 -0.4064)
			(end -0.7874 0.4064)
			(stroke
				(width 0.1524)
				(type default)
			)
			(layer "B.SilkS")
		)
		(fp_line
			(start 0.7874 -0.4064)
			(end -0.7874 -0.4064)
			(stroke
				(width 0.1524)
				(type default)
			)
			(layer "B.SilkS")
		)
		(fp_poly
			(pts
				(xy 0.5334 0.254) (xy 0.635 0.254) (xy 0.635 0.2286) (xy 0.635 -0.254) (xy 0.5334 -0.254) (xy 0.5334 -0.2794)
				(xy -0.5334 -0.2794) (xy -0.5334 -0.254) (xy -0.635 -0.254) (xy -0.635 0.254) (xy -0.5334 0.254)
				(xy -0.5334 0.2794) (xy 0.508 0.2794) (xy 0.5334 0.2794)
			)
			(stroke
				(width 0)
				(type default)
			)
			(fill no)
			(layer "B.CrtYd")
		)
		(pad "1" smd rect
			(at -0.40005 0 90)
			(size 0.4572 0.508)
			(layers "B.Cu" "B.Mask" "B.Paste")
			(net "UART_T1_NODE3_RXD")
		)
		(pad "2" smd rect
			(at 0.40005 0 90)
			(size 0.4572 0.508)
			(layers "B.Cu" "B.Mask" "B.Paste")
			(net "GND")
		)
	)
	(footprint ""
		(layer "B.Cu")
		(at 144.909032 -40.742616 180)
		(property "Reference" "R814"
			(at -1.24714 -17.357344 0)
			(unlocked yes)
			(layer "B.SilkS")
			(effects
				(font
					(size 0.7874 0.5842)
					(thickness 0.1524)
				)
				(justify left mirror)
			)
		)
		(property "Value" ""
			(at 0 0 0)
			(layer "B.Fab")
			(effects
				(font
					(size 1.27 1.27)
				)
				(justify mirror)
			)
		)
		(duplicate_pad_numbers_are_jumpers no)
		(fp_line
			(start 0.7874 0.4064)
			(end 0.7874 -0.4064)
			(stroke
				(width 0.1524)
				(type default)
			)
			(layer "B.SilkS")
		)
		(fp_line
			(start 0.7874 -0.4064)
			(end -0.7874 -0.4064)
			(stroke
				(width 0.1524)
				(type default)
			)
			(layer "B.SilkS")
		)
		(fp_line
			(start -0.7874 0.4064)
			(end 0.7874 0.4064)
			(stroke
				(width 0.1524)
				(type default)
			)
			(layer "B.SilkS")
		)
		(fp_line
			(start -0.7874 -0.4064)
			(end -0.7874 0.4064)
			(stroke
				(width 0.1524)
				(type default)
			)
			(layer "B.SilkS")
		)
		(fp_poly
			(pts
				(xy 0.508 0.2794) (xy 0.508 0.2286) (xy 0.635 0.2286) (xy 0.635 -0.254) (xy 0.5334 -0.254) (xy 0.5334 -0.2794)
				(xy -0.5334 -0.2794) (xy -0.5334 -0.254) (xy -0.635 -0.254) (xy -0.635 0.254) (xy -0.5334 0.254)
				(xy -0.5334 0.2794)
			)
			(stroke
				(width 0)
				(type default)
			)
			(fill no)
			(layer "B.CrtYd")
		)
		(pad "1" smd rect
			(at -0.40005 0)
			(size 0.4572 0.508)
			(layers "B.Cu" "B.Mask" "B.Paste")
			(net "P3V3_NODE1")
		)
		(pad "2" smd rect
			(at 0.40005 0)
			(size 0.4572 0.508)
			(layers "B.Cu" "B.Mask" "B.Paste")
			(net "UART_RI_P1_N")
		)
	)
	(footprint ""
		(layer "B.Cu")
		(at 62.189614 -136.090406)
		(property "Reference" "C274"
			(at -40.642032 52.92217 0)
			(unlocked yes)
			(layer "B.SilkS")
			(effects
				(font
					(size 0.7874 0.5842)
					(thickness 0.1524)
				)
				(justify left mirror)
			)
		)
		(property "Value" ""
			(at 0 0 0)
			(layer "B.Fab")
			(effects
				(font
					(size 1.27 1.27)
				)
				(justify mirror)
			)
		)
		(duplicate_pad_numbers_are_jumpers no)
		(fp_line
			(start -0.7874 -0.4064)
			(end -0.7874 0.4064)
			(stroke
				(width 0.1524)
				(type default)
			)
			(layer "B.SilkS")
		)
		(fp_line
			(start -0.7874 0.4064)
			(end 0.7874 0.4064)
			(stroke
				(width 0.1524)
				(type default)
			)
			(layer "B.SilkS")
		)
		(fp_line
			(start 0 0.381)
			(end 0 -0.381)
			(stroke
				(width 0.1524)
				(type default)
			)
			(layer "B.SilkS")
		)
		(fp_line
			(start 0.7874 -0.4064)
			(end -0.7874 -0.4064)
			(stroke
				(width 0.1524)
				(type default)
			)
			(layer "B.SilkS")
		)
		(fp_line
			(start 0.7874 0.4064)
			(end 0.7874 -0.4064)
			(stroke
				(width 0.1524)
				(type default)
			)
			(layer "B.SilkS")
		)
		(fp_poly
			(pts
				(xy 0.5334 0.254) (xy 0.635 0.254) (xy 0.635 0.2286) (xy 0.635 -0.254) (xy 0.5334 -0.254) (xy 0.5334 -0.2794)
				(xy -0.5334 -0.2794) (xy -0.5334 -0.254) (xy -0.635 -0.254) (xy -0.635 0.254) (xy -0.5334 0.254)
				(xy -0.5334 0.2794) (xy 0.508 0.2794) (xy 0.5334 0.2794)
			)
			(stroke
				(width 0)
				(type default)
			)
			(fill no)
			(layer "B.CrtYd")
		)
		(pad "1" smd rect
			(at -0.40005 0 180)
			(size 0.4572 0.508)
			(layers "B.Cu" "B.Mask" "B.Paste")
			(net "P1V538_BMC_NODE1")
		)
		(pad "2" smd rect
			(at 0.40005 0 180)
			(size 0.4572 0.508)
			(layers "B.Cu" "B.Mask" "B.Paste")
			(net "GND")
		)
	)
	(footprint ""
		(layer "B.Cu")
		(at 54.469538 -88.040718 90)
		(property "Reference" "C91"
			(at 2.538222 0.924052 270)
			(unlocked yes)
			(layer "B.SilkS")
			(effects
				(font
					(size 0.7874 0.5842)
					(thickness 0.1524)
				)
				(justify mirror)
			)
		)
		(property "Value" ""
			(at 0 0 90)
			(layer "B.Fab")
			(effects
				(font
					(size 1.27 1.27)
				)
				(justify mirror)
			)
		)
		(duplicate_pad_numbers_are_jumpers no)
		(fp_line
			(start 1.2954 -0.5842)
			(end -1.2954 -0.5842)
			(stroke
				(width 0.1524)
				(type default)
			)
			(layer "B.SilkS")
		)
		(fp_line
			(start 0 -0.5842)
			(end 0 0.5842)
			(stroke
				(width 0.1524)
				(type default)
			)
			(layer "B.SilkS")
		)
		(fp_line
			(start -1.2954 -0.5842)
			(end -1.2954 0.5842)
			(stroke
				(width 0.1524)
				(type default)
			)
			(layer "B.SilkS")
		)
		(fp_line
			(start 1.2954 0.5842)
			(end 1.2954 -0.5842)
			(stroke
				(width 0.1524)
				(type default)
			)
			(layer "B.SilkS")
		)
		(fp_line
			(start -1.2954 0.5842)
			(end 1.2954 0.5842)
			(stroke
				(width 0.1524)
				(type default)
			)
			(layer "B.SilkS")
		)
		(fp_poly
			(pts
				(xy -0.8636 -0.4572) (xy -0.8636 -0.3556) (xy -1.143 -0.3556) (xy -1.143 0.3556) (xy -0.8636 0.3556)
				(xy -0.8636 0.4572) (xy 0.8636 0.4572) (xy 0.8636 0.3556) (xy 1.143 0.3556) (xy 1.143 -0.3556) (xy 0.8636 -0.3556)
				(xy 0.8636 -0.4572)
			)
			(stroke
				(width 0)
				(type default)
			)
			(fill no)
			(layer "B.CrtYd")
		)
		(fp_line
			(start 0.884936 -0.504952)
			(end -0.884936 -0.504952)
			(stroke
				(width 0.1)
				(type default)
			)
			(layer "B.Fab")
		)
		(fp_line
			(start -0.884936 -0.504952)
			(end -0.884936 0.504952)
			(stroke
				(width 0.1)
				(type default)
			)
			(layer "B.Fab")
		)
		(fp_line
			(start 0.884936 0.504952)
			(end 0.884936 -0.504952)
			(stroke
				(width 0.1)
				(type default)
			)
			(layer "B.Fab")
		)
		(fp_line
			(start -0.884936 0.504952)
			(end 0.884936 0.504952)
			(stroke
				(width 0.1)
				(type default)
			)
			(layer "B.Fab")
		)
		(pad "1" smd rect
			(at -0.7366 0 180)
			(size 0.7112 0.8128)
			(layers "B.Cu" "B.Mask" "B.Paste")
			(net "P1V8_NODE1")
		)
		(pad "2" smd rect
			(at 0.7366 0 180)
			(size 0.7112 0.8128)
			(layers "B.Cu" "B.Mask" "B.Paste")
			(net "GND")
		)
	)
	(footprint ""
		(layer "B.Cu")
		(at 41.670732 -94.40037 90)
		(property "Reference" "R121"
			(at -4.703318 -4.56311 270)
			(unlocked yes)
			(layer "B.SilkS")
			(effects
				(font
					(size 0.7874 0.5842)
					(thickness 0.1524)
				)
				(justify left mirror)
			)
		)
		(property "Value" ""
			(at 0 0 90)
			(layer "B.Fab")
			(effects
				(font
					(size 1.27 1.27)
				)
				(justify mirror)
			)
		)
		(duplicate_pad_numbers_are_jumpers no)
		(fp_line
			(start 0.7874 -0.4064)
			(end -0.7874 -0.4064)
			(stroke
				(width 0.1524)
				(type default)
			)
			(layer "B.SilkS")
		)
		(fp_line
			(start -0.7874 -0.4064)
			(end -0.7874 0.4064)
			(stroke
				(width 0.1524)
				(type default)
			)
			(layer "B.SilkS")
		)
		(fp_line
			(start 0.7874 0.4064)
			(end 0.7874 -0.4064)
			(stroke
				(width 0.1524)
				(type default)
			)
			(layer "B.SilkS")
		)
		(fp_line
			(start -0.7874 0.4064)
			(end 0.7874 0.4064)
			(stroke
				(width 0.1524)
				(type default)
			)
			(layer "B.SilkS")
		)
		(fp_poly
			(pts
				(xy 0.508 0.2794) (xy 0.508 0.2286) (xy 0.635 0.2286) (xy 0.635 -0.254) (xy 0.5334 -0.254) (xy 0.5334 -0.2794)
				(xy -0.5334 -0.2794) (xy -0.5334 -0.254) (xy -0.635 -0.254) (xy -0.635 0.254) (xy -0.5334 0.254)
				(xy -0.5334 0.2794)
			)
			(stroke
				(width 0)
				(type default)
			)
			(fill no)
			(layer "B.CrtYd")
		)
		(pad "1" smd rect
			(at -0.40005 0 270)
			(size 0.4572 0.508)
			(layers "B.Cu" "B.Mask" "B.Paste")
			(net "SMB_CPU_NODE1_XDP_CLK_R")
		)
		(pad "2" smd rect
			(at 0.40005 0 270)
			(size 0.4572 0.508)
			(layers "B.Cu" "B.Mask" "B.Paste")
			(net "SMB_CPU_NODE1_XDP_CLK")
		)
	)
	(footprint ""
		(layer "B.Cu")
		(at 125.892052 -144.22755 180)
		(property "Reference" "C896"
			(at 3.260598 3.312414 0)
			(unlocked yes)
			(layer "B.SilkS")
			(effects
				(font
					(size 0.7874 0.5842)
					(thickness 0.1524)
				)
				(justify left mirror)
			)
		)
		(property "Value" ""
			(at 0 0 0)
			(layer "B.Fab")
			(effects
				(font
					(size 1.27 1.27)
				)
				(justify mirror)
			)
		)
		(duplicate_pad_numbers_are_jumpers no)
		(fp_line
			(start 0.7874 0.4064)
			(end 0.7874 -0.4064)
			(stroke
				(width 0.1524)
				(type default)
			)
			(layer "B.SilkS")
		)
		(fp_line
			(start 0.7874 -0.4064)
			(end -0.7874 -0.4064)
			(stroke
				(width 0.1524)
				(type default)
			)
			(layer "B.SilkS")
		)
		(fp_line
			(start 0 0.381)
			(end 0 -0.381)
			(stroke
				(width 0.1524)
				(type default)
			)
			(layer "B.SilkS")
		)
		(fp_line
			(start -0.7874 0.4064)
			(end 0.7874 0.4064)
			(stroke
				(width 0.1524)
				(type default)
			)
			(layer "B.SilkS")
		)
		(fp_line
			(start -0.7874 -0.4064)
			(end -0.7874 0.4064)
			(stroke
				(width 0.1524)
				(type default)
			)
			(layer "B.SilkS")
		)
		(fp_poly
			(pts
				(xy 0.5334 0.254) (xy 0.635 0.254) (xy 0.635 0.2286) (xy 0.635 -0.254) (xy 0.5334 -0.254) (xy 0.5334 -0.2794)
				(xy -0.5334 -0.2794) (xy -0.5334 -0.254) (xy -0.635 -0.254) (xy -0.635 0.254) (xy -0.5334 0.254)
				(xy -0.5334 0.2794) (xy 0.508 0.2794) (xy 0.5334 0.2794)
			)
			(stroke
				(width 0)
				(type default)
			)
			(fill no)
			(layer "B.CrtYd")
		)
		(pad "1" smd rect
			(at -0.40005 0)
			(size 0.4572 0.508)
			(layers "B.Cu" "B.Mask" "B.Paste")
			(net "P1V0_PCI_SW_A")
		)
		(pad "2" smd rect
			(at 0.40005 0)
			(size 0.4572 0.508)
			(layers "B.Cu" "B.Mask" "B.Paste")
			(net "GND")
		)
	)
	(footprint ""
		(layer "B.Cu")
		(at 121.72061 -35.398456 180)
		(property "Reference" "R1201"
			(at 3.310636 -0.941578 0)
			(unlocked yes)
			(layer "B.SilkS")
			(effects
				(font
					(size 0.7874 0.5842)
					(thickness 0.1524)
				)
				(justify left mirror)
			)
		)
		(property "Value" ""
			(at 0 0 0)
			(layer "B.Fab")
			(effects
				(font
					(size 1.27 1.27)
				)
				(justify mirror)
			)
		)
		(duplicate_pad_numbers_are_jumpers no)
		(fp_line
			(start 0.7874 0.4064)
			(end 0.7874 -0.4064)
			(stroke
				(width 0.1524)
				(type default)
			)
			(layer "B.SilkS")
		)
		(fp_line
			(start 0.7874 -0.4064)
			(end -0.7874 -0.4064)
			(stroke
				(width 0.1524)
				(type default)
			)
			(layer "B.SilkS")
		)
		(fp_line
			(start -0.7874 0.4064)
			(end 0.7874 0.4064)
			(stroke
				(width 0.1524)
				(type default)
			)
			(layer "B.SilkS")
		)
		(fp_line
			(start -0.7874 -0.4064)
			(end -0.7874 0.4064)
			(stroke
				(width 0.1524)
				(type default)
			)
			(layer "B.SilkS")
		)
		(fp_poly
			(pts
				(xy 0.508 0.2794) (xy 0.508 0.2286) (xy 0.635 0.2286) (xy 0.635 -0.254) (xy 0.5334 -0.254) (xy 0.5334 -0.2794)
				(xy -0.5334 -0.2794) (xy -0.5334 -0.254) (xy -0.635 -0.254) (xy -0.635 0.254) (xy -0.5334 0.254)
				(xy -0.5334 0.2794)
			)
			(stroke
				(width 0)
				(type default)
			)
			(fill no)
			(layer "B.CrtYd")
		)
		(pad "1" smd rect
			(at -0.40005 0)
			(size 0.4572 0.508)
			(layers "B.Cu" "B.Mask" "B.Paste")
			(net "SIO_JTAG_CPLD3_TMS_R")
		)
		(pad "2" smd rect
			(at 0.40005 0)
			(size 0.4572 0.508)
			(layers "B.Cu" "B.Mask" "B.Paste")
			(net "P3V3_NODE1")
		)
	)
)
